# S9S_MB_2U (Grand Teton) — schematic netlist excerpt (pin names and nets, part order shuffled) for the footprints in the layout excerpt that follows; sources: Cadence DE-HDL packaged netlist, KiCad conversion of 03242023_DA0F0TMBIJ0_F0T_Motherboard_J_brd_V01_OCP.brd

R3685  Q_RES  0 5% EMPTY  pkg 0402LF  page 250 : A = P5V_ADC ; B = P5V_ADC_MAM

(kicad_pcb
	(version 20260206)
	(generator "pcbnew")
	(generator_version "10.0")
	(general
		(thickness 1.6)
		(legacy_teardrops no)
	)
	(paper "A4")
	(title_block
		(title "03242023_DA0F0TMBIJ0_F0T_Motherboard_J_brd_V01_OCP.brd")
		(comment 1 "Grand Teton / footprints 2189-2189 of 6105")
	)
	(layers
		(0 "F.Cu" signal "TOP")
		(4 "In1.Cu" signal "GND")
		(6 "In2.Cu" signal "IN1")
		(8 "In3.Cu" signal "GND1")
		(10 "In4.Cu" signal "IN2")
		(12 "In5.Cu" signal "GND2")
		(14 "In6.Cu" signal "IN3")
		(16 "In7.Cu" signal "GND3")
		(18 "In8.Cu" signal "VCC")
		(20 "In9.Cu" signal "VCC1")
		(22 "In10.Cu" signal "GND4")
		(24 "In11.Cu" signal "IN4")
		(26 "In12.Cu" signal "GND5")
		(28 "In13.Cu" signal "IN5")
		(30 "In14.Cu" signal "GND6")
		(32 "In15.Cu" signal "IN6")
		(34 "In16.Cu" signal "GND7")
		(2 "B.Cu" signal "BOTTOM")
		(9 "F.Adhes" user "F.Adhesive")
		(11 "B.Adhes" user "B.Adhesive")
		(13 "F.Paste" user "Package Geometry/Pastemask Top")
		(15 "B.Paste" user "Package Geometry/Pastemask Bottom")
		(5 "F.SilkS" user "Ref Des/Silkscreen Top")
		(7 "B.SilkS" user "Ref Des/Silkscreen Bottom")
		(1 "F.Mask" user "Board Geometry/Soldermask Top")
		(3 "B.Mask" user "Board Geometry/Soldermask Bottom")
		(17 "Dwgs.User" user "User.Drawings")
		(19 "Cmts.User" user "User.Comments")
		(21 "Eco1.User" user "User.Eco1")
		(23 "Eco2.User" user "User.Eco2")
		(25 "Edge.Cuts" user "Board Geometry/Outline")
		(27 "Margin" user)
		(31 "F.CrtYd" user "Package Geometry/Place Bound Top")
		(29 "B.CrtYd" user "Package Geometry/Place Bound Bottom")
		(35 "F.Fab" user "Ref Des/Assembly Top")
		(33 "B.Fab" user "Ref Des/Assembly Bottom")
	)
	(footprint ""
		(layer "F.Cu")
		(at 40.627554 -109.444282)
		(property "Reference" "R3685"
			(at 0 0 0)
			(layer "F.SilkS")
			(hide yes)
			(effects
				(font
					(size 1.27 1.27)
				)
			)
		)
		(property "Value" ""
			(at 0 0 0)
			(layer "F.Fab")
			(effects
				(font
					(size 1.27 1.27)
				)
			)
		)
		(duplicate_pad_numbers_are_jumpers no)
		(fp_line
			(start -0.7874 -0.4064)
			(end 0.7874 -0.4064)
			(stroke
				(width 0.1524)
				(type default)
			)
			(layer "F.SilkS")
		)
		(fp_line
			(start -0.7874 0.4064)
			(end -0.7874 -0.4064)
			(stroke
				(width 0.1524)
				(type default)
			)
			(layer "F.SilkS")
		)
		(fp_line
			(start 0.7874 -0.4064)
			(end 0.7874 0.4064)
			(stroke
				(width 0.1524)
				(type default)
			)
			(layer "F.SilkS")
		)
		(fp_line
			(start 0.7874 0.4064)
			(end -0.7874 0.4064)
			(stroke
				(width 0.1524)
				(type default)
			)
			(layer "F.SilkS")
		)
		(fp_line
			(start -0.67945 -0.305054)
			(end -0.12065 -0.305054)
			(stroke
				(width 0.1)
				(type default)
			)
			(layer "F.Fab")
		)
		(fp_line
			(start -0.67945 0.3048)
			(end -0.67945 -0.305054)
			(stroke
				(width 0.1)
				(type default)
			)
			(layer "F.Fab")
		)
		(fp_line
			(start -0.12065 -0.305054)
			(end -0.12065 -0.2794)
			(stroke
				(width 0.1)
				(type default)
			)
			(layer "F.Fab")
		)
		(fp_line
			(start -0.12065 -0.2794)
			(end 0.12065 -0.2794)
			(stroke
				(width 0.1)
				(type default)
			)
			(layer "F.Fab")
		)
		(fp_line
			(start -0.12065 0.2794)
			(end -0.12065 0.3048)
			(stroke
				(width 0.1)
				(type default)
			)
			(layer "F.Fab")
		)
		(fp_line
			(start -0.12065 0.3048)
			(end -0.67945 0.3048)
			(stroke
				(width 0.1)
				(type default)
			)
			(layer "F.Fab")
		)
		(fp_line
			(start 0.120396 0.2794)
			(end -0.12065 0.2794)
			(stroke
				(width 0.1)
				(type default)
			)
			(layer "F.Fab")
		)
		(fp_line
			(start 0.120396 0.3048)
			(end 0.120396 0.2794)
			(stroke
				(width 0.1)
				(type default)
			)
			(layer "F.Fab")
		)
		(fp_line
			(start 0.12065 -0.3048)
			(end 0.67945 -0.3048)
			(stroke
				(width 0.1)
				(type default)
			)
			(layer "F.Fab")
		)
		(fp_line
			(start 0.12065 -0.2794)
			(end 0.12065 -0.3048)
			(stroke
				(width 0.1)
				(type default)
			)
			(layer "F.Fab")
		)
		(fp_line
			(start 0.67945 -0.3048)
			(end 0.67945 0.3048)
			(stroke
				(width 0.1)
				(type default)
			)
			(layer "F.Fab")
		)
		(fp_line
			(start 0.67945 0.3048)
			(end 0.120396 0.3048)
			(stroke
				(width 0.1)
				(type default)
			)
			(layer "F.Fab")
		)
		(pad "1" smd rect
			(at -0.40005 0 180)
			(size 0.4572 0.508)
			(layers "F.Cu" "F.Mask" "F.Paste")
			(net "P5V_ADC")
		)
		(pad "2" smd rect
			(at 0.40005 0 180)
			(size 0.4572 0.508)
			(layers "F.Cu" "F.Mask" "F.Paste")
			(net "P5V_ADC_MAM")
		)
	)
)
